FILE_TYPE = CONNECTIVITY;
{Allegro Design Entry HDL 17.2-2016 S081 (4005846) 1/11/2022}
"PAGE_NUMBER" = 178;
0"NC";
1"GND\g";
2"GND\g";
3"GND\g";
4"GND\g";
5"GND\g";
6"GND\g";
7"GND\g";
8"GND\g";
9"GND\g";
10"GND\g";
11"GND\g";
12"SW_PVDDCR_CPU1_P0_BOOT6_R";
13"SW_PVDDCR_CPU1_P0_BOOT5_R";
14"SW_PVDDCR_CPU1_P0_BOOTR5";
15"GND\g";
16"GND\g";
17"IND_CPU1_P0_CPL5";
18"IND_CPU1_P0_CPL6";
19"SW_PVDDCR_CPU1_P0_SW5";
20"SW_PVDDCR_CPU1_P0_SW5_RC";
21"GND\g";
22"PVDDCR_CPU1_P0\g";
23"IND_CPU1_P0_CPL6";
24"SW_PVDDCR_CPU1_P0_BOOT6";
25"SW_PVDDCR_CPU1_P0_BOOT5";
26"NC_PVDDCR_CPU1_P0_GL1_5";
27"NC_PVDDCR_CPU1_P0_GL2_5";
28"SW_P12V_STBY_PVDDCR_CPU1_P0_FLT\g";
29"NC_PVDDCR_CPU1_P0_DNC5";
30"PVDDCR_CPU1_P0_IMON5";
31"PVDDCR_CPU1_P0_VCC5";
32"PVDDCR_CPU1_P0_PVCC\g";
33"PVDDCR_CPU1_P0_VCCS"CDS_PHYS_NET_NAME"PVCCIN_CPU0_VREF";
34"PVDDCR_CPU1_P0_LSET5";
35"NC_PVDDCR_CPU1_P0_DNC6";
36"PVDDCR_CPU1_P0_TEMP0";
37"PVDDCR_CPU1_P0_PWM5";
38"PVDDCR_CPU1_P0_IMON6";
39"PVDDCR_CPU1_P0_PVCC\g";
40"PVDDCR_CPU1_P0_VCCS"CDS_PHYS_NET_NAME"PVCCIN_CPU0_VREF";
41"PVDDCR_CPU1_P0_VCC6";
42"GND\g";
43"PVDDCR_CPU1_P0\g";
44"GND\g";
45"SW_PVDDCR_CPU1_P0_BOOTR6";
46"IND_CPU1_P0_CPL0";
47"PVDDCR_CPU1_P0_VOS5";
48"SW_P12V_STBY_PVDDCR_CPU1_P0_FLT\g";
49"GND\g";
50"SW_PVDDCR_CPU1_P0_SW6";
51"NC_PVDDCR_CPU1_P0_GL1_6";
52"NC_PVDDCR_CPU1_P0_GL2_6";
53"SW_PVDDCR_CPU1_P0_SW6_RC";
54"PVDDCR_CPU1_P0_LSET6";
55"PVDDCR_CPU1_P0_TEMP0";
56"PVDDCR_CPU1_P0_PWM6";
57"PVDDCR_CPU1_P0_VOS6";
%"Q_CAP"
"1","(5775,2800)","0","pure_quanta","I100";
;
LOCATION"PC119_6"
$SEC"1"
CDS_SEC"1"
TOLERANCE"10%"
VOLTAGE"25V"
VALUE"10UF"
MATERIAL"X6S"
PART_NUMBER"CH6104KEA00"
PACK_TYPE"C0805"
CDS_LIB"pure_quanta";
"B"
$PN"2"49;
"A"
$PN"1"48;
%"Q_CAP"
"1","(5400,2800)","0","pure_quanta","I101";
;
LOCATION"PC118_6"
$SEC"1"
CDS_SEC"1"
PART_NUMBER"CH6104KEA00"
MATERIAL"X6S"
TOLERANCE"10%"
VALUE"10UF"
VOLTAGE"25V"
PACK_TYPE"C0805"
CDS_LIB"pure_quanta";
"B"
$PN"2"49;
"A"
$PN"1"48;
%"UNIVERSAL_GND"
"1","(5775,2450)","0","pure_quanta_power","I102";
;
CDS_LIB"pure_quanta_power"
HDL_POWER"GND";
"A"49;
%"Q_CAP"
"1","(5300,2125)","0","pure_quanta","I103";
;
LOCATION"PC117"
$SEC"1"
CDS_SEC"1"
PART_NUMBER"CH4223K1B00"
VALUE"0.22UF"
VOLTAGE"16V"
TOLERANCE"10%"
MATERIAL"X7R"
PACK_TYPE"0402"
CDS_LIB"pure_quanta";
"B"
$PN"2"45;
"A"
$PN"1"12;
%"Q_CAP"
"1","(5000,2800)","0","pure_quanta","I105";
;
LOCATION"PC116_6"
$SEC"1"
CDS_SEC"1"
PACK_TYPE"C0805"
PART_NUMBER"CH6104KEA00"
MATERIAL"X6S"
TOLERANCE"10%"
VALUE"10UF"
VOLTAGE"25V"
CDS_LIB"pure_quanta";
"B"
$PN"2"49;
"A"
$PN"1"48;
%"Q_CAP"
"1","(4600,2800)","0","pure_quanta","I106";
;
LOCATION"PC115_6"
$SEC"1"
CDS_SEC"1"
MATERIAL"X6S"
TOLERANCE"10%"
VALUE"1UF"
PART_NUMBER"CH5104KEB02"
VOLTAGE"25V"
PACK_TYPE"C0402"
CDS_LIB"pure_quanta";
"B"
$PN"2"49;
"A"
$PN"1"48;
%"Q_CAP"
"1","(4175,2800)","0","pure_quanta","I107";
;
LOCATION"PC114_6"
$SEC"1"
CDS_SEC"1"
MATERIAL"X7R"
TOLERANCE"10%"
VALUE"0.1UF"
PART_NUMBER"CH4104K1B00"
VOLTAGE"25V"
PACK_TYPE"0402"
CDS_LIB"pure_quanta";
"B"
$PN"2"49;
"A"
$PN"1"48;
%"Q_RES"
"1","(4575,2250)","0","pure_quanta","I108";
;
LOCATION"PR420"
$SEC"1"
CDS_SEC"1"
TOLERANCE"1%"
MATERIAL"CHIP"
PACK_TYPE"0402LF"
WATTAGE"1/16W"
VALUE"4.7"
PART_NUMBER"CS-4702FB19"
CDS_LIB"pure_quanta";
"B"
$PN"2"12;
"A"
$PN"1"24;
%"UNIVERSAL_GND"
"1","(8050,1350)","0","pure_quanta_power","I109";
;
CDS_LIB"pure_quanta_power"
HDL_POWER"GND";
"A"21;
%"Q_RES"
"1","(5925,775)","0","pure_quanta","I110";
;
LOCATION"PR421"
$SEC"1"
CDS_SEC"1"
PART_NUMBER"CS00002JB38"
WATTAGE"1/16W"
MATERIAL"CHIP"
TOLERANCE"5%"
VALUE"0"
PACK_TYPE"0402LF"
CDS_LIB"pure_quanta";
"B"
$PN"2"22;
"A"
$PN"1"57;
%"Q_CAP"
"1","(2200,2900)","0","pure_quanta","I111";
;
LOCATION"PC113_C1P0_6"
$SEC"1"
CDS_SEC"1"
MATERIAL"X6S"
TOLERANCE"10%"
VALUE"2.2UF"
PART_NUMBER"CH5222KEB01"
VOLTAGE"10V"
PACK_TYPE"C0402"
CDS_LIB"pure_quanta";
"B"
$PN"2"1;
"A"
$PN"1"39;
%"UNIVERSAL_GND"
"1","(2200,2625)","0","pure_quanta_power","I112";
;
CDS_LIB"pure_quanta_power"
HDL_POWER"GND";
"A"1;
%"Q_RES"
"2","(1850,2875)","0","pure_quanta","I114";
;
LOCATION"PR416"
$SEC"1"
CDS_SEC"1"
WATTAGE"1/16W"
MATERIAL"CHIP"
TOLERANCE"1%"
VALUE"2.2"
PART_NUMBER"CS-2202FB00"
PACK_TYPE"0402LF"
CDS_LIB"pure_quanta";
"A"
$PN"1"39;
"B"
$PN"2"41;
%"Q_CAP"
"1","(1850,2325)","0","pure_quanta","I115";
;
LOCATION"PC112"
$SEC"1"
CDS_SEC"1"
MATERIAL"X6S"
TOLERANCE"10%"
VALUE"2.2UF"
PART_NUMBER"CH5222KEB01"
VOLTAGE"10V"
PACK_TYPE"C0402"
CDS_LIB"pure_quanta";
"B"
$PN"2"2;
"A"
$PN"1"41;
%"UNIVERSAL_GND"
"1","(1850,2125)","0","pure_quanta_power","I116";
;
CDS_LIB"pure_quanta_power"
HDL_POWER"GND";
"A"2;
%"UNIVERSAL_GND"
"1","(3975,1175)","0","pure_quanta_power","I119";
;
CDS_LIB"pure_quanta_power"
HDL_POWER"GND";
"A"44;
%"ISL99390FRZTR5935"
"1","(3325,1900)","0","pure_quanta","I120";
;
LOCATION"PU11"
$SEC"1"
CDS_SEC"1"
PART_TYPE"SMLF"
MATERIAL"IC"
VALUE"ISL99390FRZ-TR5935"
PART_NUMBER"AL099390004"
NEEDS_NO_SIZE"TRUE"
CDS_LMAN_SYM_OUTLINE"-300,700,250,-650"
CDS_LIB"pure_quanta";
"PGND2"
$PN"7_9-20_24"44;
"GL2"
$PN"41"52;
"GL1"
$PN"6"51;
"DNC"
$PN"31"35;
"EN"
$PN"35"41;
"PGND3"
$PN"40"44;
"VOS"
$PN"1"57;
"VIN2"
$PN"30"48;
"PGND1"
$PN"5"44;
"SW"
$PN"10_19"50;
"LSET"
$PN"37"54;
"IOUT"
$PN"38"38;
"TOUT_FLT"
$PN"36"55;
"PVCC"
$PN"4"39;
"PHASE"
$PN"32"45;
"VIN1"
$PN"25_29"48;
"BOOT"
$PN"33"24;
"AGND"
$PN"2"44;
"VCC"
$PN"3"41;
"REFIN"
$PN"39"40;
"PWM"
$PN"34"56;
%"Q_RES"
"2","(1400,1400)","2","pure_quanta","I123";
;
LOCATION"PR7"
$SEC"1"
CDS_SEC"1"
WATTAGE"1/16W"
MATERIAL"EMPTY"
TOLERANCE"1%"
VALUE"8.87K"
PART_NUMBER"CS28872FB01"
PACK_TYPE"0402LF"
CDS_LIB"pure_quanta";
"A"
$PN"1"54;
"B"
$PN"2"3;
%"UNIVERSAL_GND"
"1","(1400,1175)","0","pure_quanta_power","I124";
;
CDS_LIB"pure_quanta_power"
HDL_POWER"GND";
"A"3;
%"Q_CAP"
"1","(900,1525)","0","pure_quanta","I125";
;
LOCATION"PC111_6"
$SEC"1"
CDS_SEC"1"
MATERIAL"X7R"
TOLERANCE"10%"
VALUE"0.1UF"
PART_NUMBER"CH4104K1B00"
VOLTAGE"25V"
PACK_TYPE"0402"
CDS_LIB"pure_quanta";
"B"
$PN"2"4;
"A"
$PN"1"40;
%"UNIVERSAL_GND"
"1","(900,1325)","0","pure_quanta_power","I126";
;
CDS_LIB"pure_quanta_power"
HDL_POWER"GND";
"A"4;
%"UNIVERSAL_GND"
"1","(4850,3600)","0","pure_quanta_power","I127";
;
CDS_LIB"pure_quanta_power"
HDL_POWER"GND";
"A"5;
%"Q_RES"
"2","(4850,3825)","0","pure_quanta","I128";
;
LOCATION"PR158"
$SEC"1"
CDS_SEC"1"
WATTAGE"1/8W"
MATERIAL"EMPTY"
TOLERANCE"1%"
VALUE"1.5"
PART_NUMBER"CS-1504FB00"
PACK_TYPE"0402LF"
CDS_LIB"pure_quanta";
"A"
$PN"1"20;
"B"
$PN"2"5;
%"Q_CAP"
"1","(4850,4350)","0","pure_quanta","I129";
;
LOCATION"PC157"
$SEC"1"
CDS_SEC"1"
MATERIAL"EMPTY"
TOLERANCE"10%"
VALUE"560PF"
PART_NUMBER"CH1566K1B09"
VOLTAGE"50V"
PACK_TYPE"C0402"
CDS_LIB"pure_quanta";
"B"
$PN"2"20;
"A"
$PN"1"19;
%"UNIVERSAL_GND"
"1","(4750,925)","0","pure_quanta_power","I130";
;
CDS_LIB"pure_quanta_power"
HDL_POWER"GND";
"A"6;
%"Q_RES"
"2","(4750,1150)","0","pure_quanta","I131";
;
LOCATION"PR155"
$SEC"1"
CDS_SEC"1"
TOLERANCE"1%"
WATTAGE"1/8W"
VALUE"1.5"
PART_NUMBER"CS-1504FB00"
PACK_TYPE"0402LF"
MATERIAL"EMPTY"
CDS_LIB"pure_quanta";
"A"
$PN"1"53;
"B"
$PN"2"6;
%"Q_CAP"
"1","(4750,1700)","0","pure_quanta","I132";
;
LOCATION"PC154"
$SEC"1"
CDS_SEC"1"
PART_NUMBER"CH1566K1B09"
VALUE"560PF"
PACK_TYPE"C0402"
MATERIAL"EMPTY"
TOLERANCE"10%"
VOLTAGE"50V"
CDS_LIB"pure_quanta";
"B"
$PN"2"53;
"A"
$PN"1"50;
%"VCC_CORE"
"1","(1875,5950)","0","pure_quanta_power","I133";
;
HDL_POWER"PVDDCR_CPU1_P0_PVCC"
CDS_LIB"pure_quanta_power";
"A"32;
%"VCC_CORE"
"1","(1850,3300)","0","pure_quanta_power","I134";
;
HDL_POWER"PVDDCR_CPU1_P0_PVCC"
CDS_LIB"pure_quanta_power";
"A"39;
%"UNIVERSAL_GND"
"1","(5100,1550)","0","pure_quanta_power","I135";
;
CDS_LIB"pure_quanta_power"
HDL_POWER"GND";
"A"7;
%"Q_INDUCTOR"
"1","(5275,1675)","2","pure_quanta","I136";
;
LOCATION"PL9"
$SEC"1"
CDS_SEC"1"
PACK_TYPE"SMLF"
MATERIAL"IND"
VALUE"0.22UH/33A"
PART_NUMBER"CV+22Y0EZ00"
NEEDS_NO_SIZE"TRUE"
CDS_LIB"pure_quanta";
"1"
$PN"1"46;
"2"
$PN"2"7;
%"UNIVERSAL_GND"
"1","(1425,3825)","0","pure_quanta_power","I20";
;
CDS_LIB"pure_quanta_power"
HDL_POWER"GND";
"A"8;
%"Q_RES"
"2","(1425,4050)","2","pure_quanta","I21";
;
LOCATION"PR93"
$SEC"1"
CDS_SEC"1"
PART_NUMBER"CS28872FB01"
WATTAGE"1/16W"
MATERIAL"EMPTY"
TOLERANCE"1%"
VALUE"8.87K"
PACK_TYPE"0402LF"
CDS_LIB"pure_quanta";
"A"
$PN"1"34;
"B"
$PN"2"8;
%"ISL99390FRZTR5935"
"1","(3350,4550)","0","pure_quanta","I31";
;
LOCATION"PU16"
$SEC"1"
CDS_SEC"1"
PART_TYPE"SMLF"
MATERIAL"IC"
VALUE"ISL99390FRZ-TR5935"
PART_NUMBER"AL099390004"
CDS_LIB"pure_quanta"
CDS_LMAN_SYM_OUTLINE"-300,700,250,-650"
NEEDS_NO_SIZE"TRUE";
"PGND2"
$PN"7_9-20_24"42;
"GL2"
$PN"41"27;
"GL1"
$PN"6"26;
"DNC"
$PN"31"29;
"EN"
$PN"35"31;
"PGND3"
$PN"40"42;
"VOS"
$PN"1"47;
"VIN2"
$PN"30"28;
"PGND1"
$PN"5"42;
"SW"
$PN"10_19"19;
"LSET"
$PN"37"34;
"IOUT"
$PN"38"30;
"TOUT_FLT"
$PN"36"36;
"PVCC"
$PN"4"32;
"PHASE"
$PN"32"14;
"VIN1"
$PN"25_29"28;
"BOOT"
$PN"33"25;
"AGND"
$PN"2"42;
"VCC"
$PN"3"31;
"REFIN"
$PN"39"33;
"PWM"
$PN"34"37;
%"UNIVERSAL_GND"
"1","(4000,3825)","0","pure_quanta_power","I36";
;
CDS_LIB"pure_quanta_power"
HDL_POWER"GND";
"A"42;
%"Q_CAP"
"1","(4625,5450)","0","pure_quanta","I39";
;
LOCATION"PC135_5"
$SEC"1"
CDS_SEC"1"
MATERIAL"X6S"
TOLERANCE"10%"
VALUE"1UF"
PART_NUMBER"CH5104KEB02"
VOLTAGE"25V"
PACK_TYPE"C0402"
CDS_LIB"pure_quanta";
"B"
$PN"2"15;
"A"
$PN"1"28;
%"Q_CAP"
"1","(5025,5450)","0","pure_quanta","I40";
;
LOCATION"PC136_5"
$SEC"1"
CDS_SEC"1"
MATERIAL"X6S"
TOLERANCE"10%"
VALUE"10UF"
VOLTAGE"25V"
PACK_TYPE"C0805"
PART_NUMBER"CH6104KEA00"
CDS_LIB"pure_quanta";
"B"
$PN"2"15;
"A"
$PN"1"28;
%"UNIVERSAL_GND"
"1","(5800,5100)","0","pure_quanta_power","I54";
;
CDS_LIB"pure_quanta_power"
HDL_POWER"GND";
"A"15;
%"Q_CAP"
"1","(5425,5450)","0","pure_quanta","I59";
;
LOCATION"PC138_5"
$SEC"1"
CDS_SEC"1"
MATERIAL"X6S"
TOLERANCE"10%"
VALUE"10UF"
PART_NUMBER"CH6104KEA00"
VOLTAGE"25V"
PACK_TYPE"C0805"
CDS_LIB"pure_quanta";
"B"
$PN"2"15;
"A"
$PN"1"28;
%"Q_CAP"
"1","(5800,5450)","0","pure_quanta","I60";
;
LOCATION"PC139_5"
$SEC"1"
CDS_SEC"1"
MATERIAL"X6S"
TOLERANCE"10%"
VALUE"10UF"
PART_NUMBER"CH6104KEA00"
VOLTAGE"25V"
PACK_TYPE"C0805"
CDS_LIB"pure_quanta";
"B"
$PN"2"15;
"A"
$PN"1"28;
%"VCC_CORE"
"1","(5800,5800)","0","pure_quanta_power","I61";
;
HDL_POWER"SW_P12V_STBY_PVDDCR_CPU1_P0_FLT"
CDS_LIB"pure_quanta_power";
"A"28;
%"Q_RES"
"1","(6000,3475)","0","pure_quanta","I76";
;
LOCATION"PR96"
$SEC"1"
CDS_SEC"1"
PART_NUMBER"CS00002JB38"
WATTAGE"1/16W"
MATERIAL"CHIP"
TOLERANCE"5%"
VALUE"0"
PACK_TYPE"0402LF"
CDS_LIB"pure_quanta";
"B"
$PN"2"43;
"A"
$PN"1"47;
%"VCC_CORE"
"1","(8075,4700)","0","pure_quanta_power","I77";
;
HDL_POWER"PVDDCR_CPU1_P0"
CDS_LIB"pure_quanta_power";
"A"43;
%"UNIVERSAL_GND"
"1","(8075,4000)","0","pure_quanta_power","I78";
;
CDS_LIB"pure_quanta_power"
HDL_POWER"GND";
"A"16;
%"Q_CAP"
"1","(8075,4350)","0","pure_quanta","I79";
;
LOCATION"PC141_5"
$SEC"1"
CDS_SEC"1"
MATERIAL"X6S"
TOLERANCE"20%"
VALUE"22UF"
PART_NUMBER"TMP_QCH622KMEA01"
VOLTAGE"4V"
PACK_TYPE"0805"
CDS_LIB"pure_quanta";
"B"
$PN"2"16;
"A"
$PN"1"43;
%"Q_CAP"
"1","(7650,4350)","0","pure_quanta","I80";
;
LOCATION"PC140_5"
$SEC"1"
CDS_SEC"1"
MATERIAL"X6S"
TOLERANCE"20%"
VALUE"22UF"
PART_NUMBER"TMP_QCH622KMEA01"
VOLTAGE"4V"
PACK_TYPE"0805"
CDS_LIB"pure_quanta";
"B"
$PN"2"16;
"A"
$PN"1"43;
%"Q_INDUCTOR4P_14"
"1","(6250,4425)","0","pure_quanta","I82";
;
LOCATION"PL15"
$SEC"1"
CDS_SEC"1"
PART_TYPE"SMLF"
MATERIAL"IND"
VALUE"150NH"
PART_NUMBER"CV+15^0TZ04"
CDS_LIB"pure_quanta"
NEEDS_NO_SIZE"TRUE";
"1"
$PN"1"19;
"4"
$PN"4"43;
"3"
$PN"3"17;
"2"
$PN"2"18;
%"Q_CAP"
"1","(925,4175)","0","pure_quanta","I83";
;
LOCATION"PC132_5"
$SEC"1"
CDS_SEC"1"
MATERIAL"X7R"
TOLERANCE"10%"
VALUE"0.1UF"
PART_NUMBER"CH4104K1B00"
VOLTAGE"25V"
PACK_TYPE"0402"
CDS_LIB"pure_quanta";
"B"
$PN"2"11;
"A"
$PN"1"33;
%"Q_CAP"
"1","(5325,4775)","0","pure_quanta","I84";
;
LOCATION"PC137"
$SEC"1"
CDS_SEC"1"
PART_NUMBER"CH4223K1B00"
MATERIAL"X7R"
TOLERANCE"10%"
VALUE"0.22UF"
VOLTAGE"16V"
PACK_TYPE"0402"
CDS_LIB"pure_quanta";
"B"
$PN"2"14;
"A"
$PN"1"13;
%"Q_RES"
"1","(4600,4900)","0","pure_quanta","I85";
;
LOCATION"PR95"
$SEC"1"
CDS_SEC"1"
PACK_TYPE"0402LF"
TOLERANCE"1%"
MATERIAL"CHIP"
WATTAGE"1/16W"
VALUE"4.7"
PART_NUMBER"CS-4702FB19"
CDS_LIB"pure_quanta";
"B"
$PN"2"13;
"A"
$PN"1"25;
%"Q_CAP"
"1","(4200,5450)","0","pure_quanta","I86";
;
LOCATION"PC134_5"
$SEC"1"
CDS_SEC"1"
MATERIAL"X7R"
TOLERANCE"10%"
VALUE"0.1UF"
PART_NUMBER"CH4104K1B00"
VOLTAGE"25V"
PACK_TYPE"0402"
CDS_LIB"pure_quanta";
"B"
$PN"2"15;
"A"
$PN"1"28;
%"Q_CAP"
"1","(1875,4975)","0","pure_quanta","I87";
;
LOCATION"PC131"
$SEC"1"
CDS_SEC"1"
MATERIAL"X6S"
TOLERANCE"10%"
VALUE"2.2UF"
PART_NUMBER"CH5222KEB01"
VOLTAGE"10V"
PACK_TYPE"C0402"
CDS_LIB"pure_quanta";
"B"
$PN"2"9;
"A"
$PN"1"31;
%"UNIVERSAL_GND"
"1","(1875,4775)","0","pure_quanta_power","I88";
;
CDS_LIB"pure_quanta_power"
HDL_POWER"GND";
"A"9;
%"UNIVERSAL_GND"
"1","(2225,5275)","0","pure_quanta_power","I89";
;
CDS_LIB"pure_quanta_power"
HDL_POWER"GND";
"A"10;
%"Q_RES"
"2","(1875,5525)","0","pure_quanta","I90";
;
LOCATION"PR94"
$SEC"1"
CDS_SEC"1"
WATTAGE"1/16W"
MATERIAL"CHIP"
TOLERANCE"1%"
VALUE"2.2"
PART_NUMBER"CS-2202FB00"
PACK_TYPE"0402LF"
CDS_LIB"pure_quanta";
"A"
$PN"1"32;
"B"
$PN"2"31;
%"Q_CAP"
"1","(2225,5550)","0","pure_quanta","I91";
;
LOCATION"PC133_C1P0_5"
$SEC"1"
CDS_SEC"1"
MATERIAL"X6S"
TOLERANCE"10%"
VALUE"2.2UF"
PART_NUMBER"CH5222KEB01"
VOLTAGE"10V"
PACK_TYPE"C0402"
CDS_LIB"pure_quanta";
"B"
$PN"2"10;
"A"
$PN"1"32;
%"UNIVERSAL_GND"
"1","(925,3975)","0","pure_quanta_power","I93";
;
CDS_LIB"pure_quanta_power"
HDL_POWER"GND";
"A"11;
%"Q_INDUCTOR4P_14"
"1","(6250,1775)","0","pure_quanta","I94";
;
LOCATION"PL7"
$SEC"1"
CDS_SEC"1"
MATERIAL"IND"
VALUE"150NH"
PART_NUMBER"CV+15^0TZ04"
PART_TYPE"SMLF"
NEEDS_NO_SIZE"TRUE"
CDS_LIB"pure_quanta";
"1"
$PN"1"50;
"4"
$PN"4"22;
"3"
$PN"3"23;
"2"
$PN"2"46;
%"VCC_CORE"
"1","(8050,2050)","0","pure_quanta_power","I95";
;
HDL_POWER"PVDDCR_CPU1_P0"
CDS_LIB"pure_quanta_power";
"A"22;
%"Q_CAP"
"1","(8050,1700)","0","pure_quanta","I96";
;
LOCATION"PC123_6"
$SEC"1"
CDS_SEC"1"
MATERIAL"X6S"
TOLERANCE"20%"
VALUE"22UF"
PART_NUMBER"TMP_QCH622KMEA01"
VOLTAGE"4V"
PACK_TYPE"0805"
CDS_LIB"pure_quanta";
"B"
$PN"2"21;
"A"
$PN"1"22;
%"Q_CAP"
"1","(7625,1700)","0","pure_quanta","I97";
;
LOCATION"PC120_6"
$SEC"1"
CDS_SEC"1"
MATERIAL"X6S"
TOLERANCE"20%"
VALUE"22UF"
PART_NUMBER"TMP_QCH622KMEA01"
VOLTAGE"4V"
PACK_TYPE"0805"
CDS_LIB"pure_quanta";
"B"
$PN"2"21;
"A"
$PN"1"22;
%"VCC_CORE"
"1","(5775,3150)","0","pure_quanta_power","I99";
;
HDL_POWER"SW_P12V_STBY_PVDDCR_CPU1_P0_FLT"
CDS_LIB"pure_quanta_power";
"A"48;
END.
